# BASEBOARD_FAB2 (Tioga Pass) — schematic netlist excerpt (pin names and nets, part order shuffled) for the footprints in the layout excerpt that follows; sources: Cadence DE-HDL packaged netlist, KiCad conversion of Wiwynn_Tioga_Pass_MB.brd

C1D14  CAP_A  22.0UF 4V 20% X6S  pkg 0603V  page 208 : A = PVCCIN_CPU1 ; B = GND
C8E19  CAP_A  0.1UF 16V 10% X7R  pkg 0402V  page 198 : A = P5V_STBY ; B = GND

(kicad_pcb
	(version 20260206)
	(generator "pcbnew")
	(generator_version "10.0")
	(general
		(thickness 1.6)
		(legacy_teardrops no)
	)
	(paper "A4")
	(title_block
		(title "Wiwynn_Tioga_Pass_MB.brd")
		(comment 1 "Tioga Pass / footprints 2124-2125 of 4770")
	)
	(layers
		(0 "F.Cu" signal "TOP")
		(4 "In1.Cu" signal "L2GND")
		(6 "In2.Cu" signal "L3")
		(8 "In3.Cu" signal "L4GND")
		(10 "In4.Cu" signal "L5")
		(12 "In5.Cu" signal "L6GND")
		(14 "In6.Cu" signal "L7VCC")
		(16 "In7.Cu" signal "L8VCC")
		(18 "In8.Cu" signal "L9GND")
		(20 "In9.Cu" signal "L10")
		(22 "In10.Cu" signal "L11GND")
		(24 "In11.Cu" signal "L12")
		(26 "In12.Cu" signal "L13GND")
		(2 "B.Cu" signal "BOTTOM")
		(9 "F.Adhes" user "F.Adhesive")
		(11 "B.Adhes" user "B.Adhesive")
		(13 "F.Paste" user "Package Geometry/Pastemask Top")
		(15 "B.Paste" user "Package Geometry/Pastemask Bottom")
		(5 "F.SilkS" user "Ref Des/Silkscreen Top")
		(7 "B.SilkS" user "Ref Des/Silkscreen Bottom")
		(1 "F.Mask" user "Board Geometry/Soldermask Top")
		(3 "B.Mask" user "Board Geometry/Soldermask Bottom")
		(17 "Dwgs.User" user "User.Drawings")
		(19 "Cmts.User" user "User.Comments")
		(21 "Eco1.User" user "User.Eco1")
		(23 "Eco2.User" user "User.Eco2")
		(25 "Edge.Cuts" user "Board Geometry/Outline")
		(27 "Margin" user)
		(31 "F.CrtYd" user "Package Geometry/Place Bound Top")
		(29 "B.CrtYd" user "Package Geometry/Place Bound Bottom")
		(35 "F.Fab" user "Ref Des/Assembly Top")
		(33 "B.Fab" user "Ref Des/Assembly Bottom")
	)
	(footprint ""
		(layer "F.Cu")
		(at 49.4284 -78.359)
		(property "Reference" "C1D14"
			(at 0 0 0)
			(layer "F.SilkS")
			(hide yes)
			(effects
				(font
					(size 1.27 1.27)
				)
			)
		)
		(property "Value" ""
			(at 0 0 0)
			(layer "F.Fab")
			(effects
				(font
					(size 1.27 1.27)
				)
			)
		)
		(duplicate_pad_numbers_are_jumpers no)
		(fp_poly
			(pts
				(xy -0.4953 -0.2032) (xy 0.4953 -0.2032) (xy 0.4953 1.6002) (xy -0.4953 1.6002)
			)
			(stroke
				(width 0)
				(type default)
			)
			(fill no)
			(layer "F.CrtYd")
		)
		(fp_line
			(start -0.4953 -0.2032)
			(end 0.4953 -0.2032)
			(stroke
				(width 0.1)
				(type default)
			)
			(layer "F.Fab")
		)
		(fp_line
			(start -0.4953 1.6002)
			(end -0.4953 -0.2032)
			(stroke
				(width 0.1)
				(type default)
			)
			(layer "F.Fab")
		)
		(fp_line
			(start 0.4953 -0.2032)
			(end 0.4953 1.6002)
			(stroke
				(width 0.1)
				(type default)
			)
			(layer "F.Fab")
		)
		(fp_line
			(start 0.4953 1.6002)
			(end -0.4953 1.6002)
			(stroke
				(width 0.1)
				(type default)
			)
			(layer "F.Fab")
		)
		(pad "1" smd rect
			(at 0 0)
			(size 0.762 0.889)
			(layers "F.Cu" "F.Mask" "F.Paste")
			(net "PVCCIN_CPU1")
		)
		(pad "2" smd rect
			(at 0 1.397)
			(size 0.762 0.889)
			(layers "F.Cu" "F.Mask" "F.Paste")
			(net "GND")
		)
		(zone
			(layer "F.Cu")
			(hatch none 0.5)
			(connect_pads
				(clearance 0)
			)
			(min_thickness 0.25)
			(keepout
				(tracks not_allowed)
				(vias allowed)
				(pads allowed)
				(copperpour not_allowed)
				(footprints allowed)
			)
			(placement
				(enabled no)
				(sheetname "")
			)
			(fill
				(thermal_gap 0.5)
				(thermal_bridge_width 0.5)
				(island_removal_mode 0)
			)
			(polygon
				(pts
					(xy 49.0474 -77.9145) (xy 49.8094 -77.9145) (xy 49.8094 -77.4065) (xy 49.0474 -77.4065)
				)
			)
		)
	)
	(footprint ""
		(layer "F.Cu")
		(at 495.22126 -25.83942 -90)
		(property "Reference" "C8E19"
			(at 0 0 270)
			(layer "F.SilkS")
			(hide yes)
			(effects
				(font
					(size 1.27 1.27)
				)
			)
		)
		(property "Value" ""
			(at 0 0 270)
			(layer "F.Fab")
			(effects
				(font
					(size 1.27 1.27)
				)
			)
		)
		(duplicate_pad_numbers_are_jumpers no)
		(fp_rect
			(start 0.3048 0.9906)
			(end -0.3048 -0.1016)
			(stroke
				(width 0)
				(type default)
			)
			(fill no)
			(layer "F.CrtYd")
		)
		(fp_line
			(start -0.3048 0.9906)
			(end 0.3048 0.9906)
			(stroke
				(width 0.1)
				(type default)
			)
			(layer "F.Fab")
		)
		(fp_line
			(start 0.3048 0.9906)
			(end 0.3048 -0.1016)
			(stroke
				(width 0.1)
				(type default)
			)
			(layer "F.Fab")
		)
		(fp_line
			(start -0.3048 -0.1016)
			(end -0.3048 0.9906)
			(stroke
				(width 0.1)
				(type default)
			)
			(layer "F.Fab")
		)
		(fp_line
			(start 0.3048 -0.1016)
			(end -0.3048 -0.1016)
			(stroke
				(width 0.1)
				(type default)
			)
			(layer "F.Fab")
		)
		(pad "1" smd rect
			(at 0 0 270)
			(size 0.508 0.508)
			(layers "F.Cu" "F.Mask" "F.Paste")
			(net "P5V_STBY")
		)
		(pad "2" smd rect
			(at 0 0.889 270)
			(size 0.508 0.508)
			(layers "F.Cu" "F.Mask" "F.Paste")
			(net "GND")
		)
		(zone
			(layer "F.Cu")
			(hatch none 0.5)
			(connect_pads
				(clearance 0)
			)
			(min_thickness 0.25)
			(keepout
				(tracks allowed)
				(vias not_allowed)
				(pads allowed)
				(copperpour not_allowed)
				(footprints allowed)
			)
			(placement
				(enabled no)
				(sheetname "")
			)
			(fill
				(thermal_gap 0.5)
				(thermal_bridge_width 0.5)
				(island_removal_mode 0)
			)
			(polygon
				(pts
					(xy 494.58626 -25.58542) (xy 494.96726 -25.58542) (xy 494.96726 -26.09342) (xy 494.58626 -26.09342)
				)
			)
		)
		(zone
			(layer "F.Cu")
			(hatch none 0.5)
			(connect_pads
				(clearance 0)
			)
			(min_thickness 0.25)
			(keepout
				(tracks not_allowed)
				(vias allowed)
				(pads allowed)
				(copperpour not_allowed)
				(footprints allowed)
			)
			(placement
				(enabled no)
				(sheetname "")
			)
			(fill
				(thermal_gap 0.5)
				(thermal_bridge_width 0.5)
				(island_removal_mode 0)
			)
			(polygon
				(pts
					(xy 494.58626 -25.58542) (xy 494.96726 -25.58542) (xy 494.96726 -26.09342) (xy 494.58626 -26.09342)
				)
			)
		)
	)
)
